# S9S_MB_2U (Grand Teton) — schematic netlist excerpt (pin names and nets, part order shuffled) for the footprints in the layout excerpt that follows; sources: Cadence DE-HDL packaged netlist, KiCad conversion of 03242023_DA0F0TMBIJ0_F0T_Motherboard_J_brd_V01_OCP.brd

C1015  Q_CAP  22UF 4V 20% X6S  pkg C0402  page 74 : A = PVCCIN_CPU0 ; B = GND
PC2151  Q_CAP  6800PF 50V 10% X7R  pkg C0402  page 162 : A = P3V3_OCP_GATE_2 ; B = GND

(kicad_pcb
	(version 20260206)
	(generator "pcbnew")
	(generator_version "10.0")
	(general
		(thickness 1.6)
		(legacy_teardrops no)
	)
	(paper "A4")
	(title_block
		(title "03242023_DA0F0TMBIJ0_F0T_Motherboard_J_brd_V01_OCP.brd")
		(comment 1 "Grand Teton / footprints 3665-3666 of 6105")
	)
	(layers
		(0 "F.Cu" signal "TOP")
		(4 "In1.Cu" signal "GND")
		(6 "In2.Cu" signal "IN1")
		(8 "In3.Cu" signal "GND1")
		(10 "In4.Cu" signal "IN2")
		(12 "In5.Cu" signal "GND2")
		(14 "In6.Cu" signal "IN3")
		(16 "In7.Cu" signal "GND3")
		(18 "In8.Cu" signal "VCC")
		(20 "In9.Cu" signal "VCC1")
		(22 "In10.Cu" signal "GND4")
		(24 "In11.Cu" signal "IN4")
		(26 "In12.Cu" signal "GND5")
		(28 "In13.Cu" signal "IN5")
		(30 "In14.Cu" signal "GND6")
		(32 "In15.Cu" signal "IN6")
		(34 "In16.Cu" signal "GND7")
		(2 "B.Cu" signal "BOTTOM")
		(9 "F.Adhes" user "F.Adhesive")
		(11 "B.Adhes" user "B.Adhesive")
		(13 "F.Paste" user "Package Geometry/Pastemask Top")
		(15 "B.Paste" user "Package Geometry/Pastemask Bottom")
		(5 "F.SilkS" user "Ref Des/Silkscreen Top")
		(7 "B.SilkS" user "Ref Des/Silkscreen Bottom")
		(1 "F.Mask" user "Board Geometry/Soldermask Top")
		(3 "B.Mask" user "Board Geometry/Soldermask Bottom")
		(17 "Dwgs.User" user "User.Drawings")
		(19 "Cmts.User" user "User.Comments")
		(21 "Eco1.User" user "User.Eco1")
		(23 "Eco2.User" user "User.Eco2")
		(25 "Edge.Cuts" user "Board Geometry/Outline")
		(27 "Margin" user)
		(31 "F.CrtYd" user "Package Geometry/Place Bound Top")
		(29 "B.CrtYd" user "Package Geometry/Place Bound Bottom")
		(35 "F.Fab" user "Ref Des/Assembly Top")
		(33 "B.Fab" user "Ref Des/Assembly Bottom")
	)
	(footprint ""
		(layer "F.Cu")
		(at 85.919818 -53.880258 -90)
		(property "Reference" "PC2151"
			(at 0 0 270)
			(layer "F.SilkS")
			(hide yes)
			(effects
				(font
					(size 1.27 1.27)
				)
			)
		)
		(property "Value" ""
			(at 0 0 270)
			(layer "F.Fab")
			(effects
				(font
					(size 1.27 1.27)
				)
			)
		)
		(duplicate_pad_numbers_are_jumpers no)
		(fp_line
			(start -0.7874 0.4064)
			(end -0.7874 -0.4064)
			(stroke
				(width 0.1524)
				(type default)
			)
			(layer "F.SilkS")
		)
		(fp_line
			(start 0.7874 0.4064)
			(end -0.7874 0.4064)
			(stroke
				(width 0.1524)
				(type default)
			)
			(layer "F.SilkS")
		)
		(fp_line
			(start -0.7874 -0.4064)
			(end 0.7874 -0.4064)
			(stroke
				(width 0.1524)
				(type default)
			)
			(layer "F.SilkS")
		)
		(fp_line
			(start 0.7874 -0.4064)
			(end 0.7874 0.4064)
			(stroke
				(width 0.1524)
				(type default)
			)
			(layer "F.SilkS")
		)
		(fp_line
			(start -0.67945 0.3048)
			(end -0.67945 -0.305054)
			(stroke
				(width 0.1)
				(type default)
			)
			(layer "F.Fab")
		)
		(fp_line
			(start -0.12065 0.3048)
			(end -0.67945 0.3048)
			(stroke
				(width 0.1)
				(type default)
			)
			(layer "F.Fab")
		)
		(fp_line
			(start 0.120396 0.3048)
			(end 0.120396 0.2794)
			(stroke
				(width 0.1)
				(type default)
			)
			(layer "F.Fab")
		)
		(fp_line
			(start 0.67945 0.3048)
			(end 0.120396 0.3048)
			(stroke
				(width 0.1)
				(type default)
			)
			(layer "F.Fab")
		)
		(fp_line
			(start -0.12065 0.2794)
			(end -0.12065 0.3048)
			(stroke
				(width 0.1)
				(type default)
			)
			(layer "F.Fab")
		)
		(fp_line
			(start 0.120396 0.2794)
			(end -0.12065 0.2794)
			(stroke
				(width 0.1)
				(type default)
			)
			(layer "F.Fab")
		)
		(fp_line
			(start -0.12065 -0.2794)
			(end 0.12065 -0.2794)
			(stroke
				(width 0.1)
				(type default)
			)
			(layer "F.Fab")
		)
		(fp_line
			(start 0.12065 -0.2794)
			(end 0.12065 -0.3048)
			(stroke
				(width 0.1)
				(type default)
			)
			(layer "F.Fab")
		)
		(fp_line
			(start 0.12065 -0.3048)
			(end 0.67945 -0.3048)
			(stroke
				(width 0.1)
				(type default)
			)
			(layer "F.Fab")
		)
		(fp_line
			(start 0.67945 -0.3048)
			(end 0.67945 0.3048)
			(stroke
				(width 0.1)
				(type default)
			)
			(layer "F.Fab")
		)
		(fp_line
			(start -0.67945 -0.305054)
			(end -0.12065 -0.305054)
			(stroke
				(width 0.1)
				(type default)
			)
			(layer "F.Fab")
		)
		(fp_line
			(start -0.12065 -0.305054)
			(end -0.12065 -0.2794)
			(stroke
				(width 0.1)
				(type default)
			)
			(layer "F.Fab")
		)
		(pad "1" smd circle
			(at -0.40005 0 270)
			(size 0 0)
			(layers "F.Cu" "F.Mask" "F.Paste")
			(net "P3V3_OCP_GATE_2")
		)
		(pad "2" smd circle
			(at 0.40005 0 270)
			(size 0 0)
			(layers "F.Cu" "F.Mask" "F.Paste")
			(net "GND")
		)
	)
	(footprint ""
		(layer "F.Cu")
		(at 353.246944 -241.976656 -90)
		(property "Reference" "C1015"
			(at 0 0 270)
			(layer "F.SilkS")
			(hide yes)
			(effects
				(font
					(size 1.27 1.27)
				)
			)
		)
		(property "Value" ""
			(at 0 0 270)
			(layer "F.Fab")
			(effects
				(font
					(size 1.27 1.27)
				)
			)
		)
		(duplicate_pad_numbers_are_jumpers no)
		(fp_line
			(start -0.7874 0.4064)
			(end -0.7874 -0.4064)
			(stroke
				(width 0.1524)
				(type default)
			)
			(layer "F.SilkS")
		)
		(fp_line
			(start 0.7874 0.4064)
			(end -0.7874 0.4064)
			(stroke
				(width 0.1524)
				(type default)
			)
			(layer "F.SilkS")
		)
		(fp_line
			(start -0.7874 -0.4064)
			(end 0.7874 -0.4064)
			(stroke
				(width 0.1524)
				(type default)
			)
			(layer "F.SilkS")
		)
		(fp_line
			(start 0.7874 -0.4064)
			(end 0.7874 0.4064)
			(stroke
				(width 0.1524)
				(type default)
			)
			(layer "F.SilkS")
		)
		(fp_line
			(start -0.67945 0.3048)
			(end -0.67945 -0.305054)
			(stroke
				(width 0.1)
				(type default)
			)
			(layer "F.Fab")
		)
		(fp_line
			(start -0.12065 0.3048)
			(end -0.67945 0.3048)
			(stroke
				(width 0.1)
				(type default)
			)
			(layer "F.Fab")
		)
		(fp_line
			(start 0.120396 0.3048)
			(end 0.120396 0.2794)
			(stroke
				(width 0.1)
				(type default)
			)
			(layer "F.Fab")
		)
		(fp_line
			(start 0.67945 0.3048)
			(end 0.120396 0.3048)
			(stroke
				(width 0.1)
				(type default)
			)
			(layer "F.Fab")
		)
		(fp_line
			(start -0.12065 0.2794)
			(end -0.12065 0.3048)
			(stroke
				(width 0.1)
				(type default)
			)
			(layer "F.Fab")
		)
		(fp_line
			(start 0.120396 0.2794)
			(end -0.12065 0.2794)
			(stroke
				(width 0.1)
				(type default)
			)
			(layer "F.Fab")
		)
		(fp_line
			(start -0.12065 -0.2794)
			(end 0.12065 -0.2794)
			(stroke
				(width 0.1)
				(type default)
			)
			(layer "F.Fab")
		)
		(fp_line
			(start 0.12065 -0.2794)
			(end 0.12065 -0.3048)
			(stroke
				(width 0.1)
				(type default)
			)
			(layer "F.Fab")
		)
		(fp_line
			(start 0.12065 -0.3048)
			(end 0.67945 -0.3048)
			(stroke
				(width 0.1)
				(type default)
			)
			(layer "F.Fab")
		)
		(fp_line
			(start 0.67945 -0.3048)
			(end 0.67945 0.3048)
			(stroke
				(width 0.1)
				(type default)
			)
			(layer "F.Fab")
		)
		(fp_line
			(start -0.67945 -0.305054)
			(end -0.12065 -0.305054)
			(stroke
				(width 0.1)
				(type default)
			)
			(layer "F.Fab")
		)
		(fp_line
			(start -0.12065 -0.305054)
			(end -0.12065 -0.2794)
			(stroke
				(width 0.1)
				(type default)
			)
			(layer "F.Fab")
		)
		(pad "1" smd circle
			(at -0.40005 0 270)
			(size 0 0)
			(layers "F.Cu" "F.Mask" "F.Paste")
			(net "PVCCIN_CPU0")
		)
		(pad "2" smd circle
			(at 0.40005 0 270)
			(size 0 0)
			(layers "F.Cu" "F.Mask" "F.Paste")
			(net "GND")
		)
	)
)
